# T6G (Grand Teton) — schematic netlist excerpt (pin names and nets, part order shuffled) for the footprints in the layout excerpt that follows; sources: Cadence DE-HDL packaged netlist, KiCad conversion of 04192023_DAF0TMB3IC0_F0TG_MB_C_brd_V02_OCP.brd

C1045  Q_CAP  4.7UF 6.3V 20% X6S  pkg 0402  page 312 : A = P0V9_CPU0_RT3_2A ; B = GND
R3244  Q_RES  0 5% CHIP  pkg 0402LF  page 138 : A = OCP_V3_2_RBT_ARB_OUT ; B = OCP_V3_2_RBT_ARB_IN_R

(kicad_pcb
	(version 20260206)
	(generator "pcbnew")
	(generator_version "10.0")
	(general
		(thickness 1.6)
		(legacy_teardrops no)
	)
	(paper "A4")
	(title_block
		(title "04192023_DAF0TMB3IC0_F0TG_MB_C_brd_V02_OCP.brd")
		(comment 1 "Grand Teton / footprints 5588-5589 of 8354")
	)
	(layers
		(0 "F.Cu" signal "TOP")
		(4 "In1.Cu" signal "GND")
		(6 "In2.Cu" signal "IN1")
		(8 "In3.Cu" signal "GND1")
		(10 "In4.Cu" signal "IN2")
		(12 "In5.Cu" signal "GND2")
		(14 "In6.Cu" signal "IN3")
		(16 "In7.Cu" signal "GND3")
		(18 "In8.Cu" signal "VCC")
		(20 "In9.Cu" signal "VCC1")
		(22 "In10.Cu" signal "GND4")
		(24 "In11.Cu" signal "IN4")
		(26 "In12.Cu" signal "GND5")
		(28 "In13.Cu" signal "IN5")
		(30 "In14.Cu" signal "GND6")
		(32 "In15.Cu" signal "IN6")
		(34 "In16.Cu" signal "GND7")
		(2 "B.Cu" signal "BOTTOM")
		(9 "F.Adhes" user "F.Adhesive")
		(11 "B.Adhes" user "B.Adhesive")
		(13 "F.Paste" user "Package Geometry/Pastemask Top")
		(15 "B.Paste" user "Package Geometry/Pastemask Bottom")
		(5 "F.SilkS" user "Ref Des/Silkscreen Top")
		(7 "B.SilkS" user "Ref Des/Silkscreen Bottom")
		(1 "F.Mask" user "Board Geometry/Soldermask Top")
		(3 "B.Mask" user "Board Geometry/Soldermask Bottom")
		(17 "Dwgs.User" user "User.Drawings")
		(19 "Cmts.User" user "User.Comments")
		(21 "Eco1.User" user "User.Eco1")
		(23 "Eco2.User" user "User.Eco2")
		(25 "Edge.Cuts" user "Board Geometry/Outline")
		(27 "Margin" user)
		(31 "F.CrtYd" user "Package Geometry/Place Bound Top")
		(29 "B.CrtYd" user "Package Geometry/Place Bound Bottom")
		(35 "F.Fab" user "Ref Des/Assembly Top")
		(33 "B.Fab" user "Ref Des/Assembly Bottom")
	)
	(footprint ""
		(layer "B.Cu")
		(at 387.291326 -398.942052 90)
		(property "Reference" "C1045"
			(at 0 0 90)
			(layer "B.SilkS")
			(hide yes)
			(effects
				(font
					(size 1.27 1.27)
				)
				(justify mirror)
			)
		)
		(property "Value" ""
			(at 0 0 90)
			(layer "B.Fab")
			(effects
				(font
					(size 1.27 1.27)
				)
				(justify mirror)
			)
		)
		(duplicate_pad_numbers_are_jumpers no)
		(fp_line
			(start 0.7874 -0.4064)
			(end -0.7874 -0.4064)
			(stroke
				(width 0.1524)
				(type default)
			)
			(layer "B.SilkS")
		)
		(fp_line
			(start -0.7874 -0.4064)
			(end -0.7874 0.4064)
			(stroke
				(width 0.1524)
				(type default)
			)
			(layer "B.SilkS")
		)
		(fp_line
			(start 0.7874 0.4064)
			(end 0.7874 -0.4064)
			(stroke
				(width 0.1524)
				(type default)
			)
			(layer "B.SilkS")
		)
		(fp_line
			(start -0.7874 0.4064)
			(end 0.7874 0.4064)
			(stroke
				(width 0.1524)
				(type default)
			)
			(layer "B.SilkS")
		)
		(fp_line
			(start 0.67945 -0.305054)
			(end 0.12065 -0.305054)
			(stroke
				(width 0.1)
				(type default)
			)
			(layer "B.Fab")
		)
		(fp_line
			(start 0.12065 -0.305054)
			(end 0.12065 -0.2794)
			(stroke
				(width 0.1)
				(type default)
			)
			(layer "B.Fab")
		)
		(fp_line
			(start -0.12065 -0.3048)
			(end -0.67945 -0.3048)
			(stroke
				(width 0.1)
				(type default)
			)
			(layer "B.Fab")
		)
		(fp_line
			(start -0.67945 -0.3048)
			(end -0.67945 0.3048)
			(stroke
				(width 0.1)
				(type default)
			)
			(layer "B.Fab")
		)
		(fp_line
			(start 0.12065 -0.2794)
			(end -0.12065 -0.2794)
			(stroke
				(width 0.1)
				(type default)
			)
			(layer "B.Fab")
		)
		(fp_line
			(start -0.12065 -0.2794)
			(end -0.12065 -0.3048)
			(stroke
				(width 0.1)
				(type default)
			)
			(layer "B.Fab")
		)
		(fp_line
			(start 0.12065 0.2794)
			(end 0.12065 0.3048)
			(stroke
				(width 0.1)
				(type default)
			)
			(layer "B.Fab")
		)
		(fp_line
			(start -0.120396 0.2794)
			(end 0.12065 0.2794)
			(stroke
				(width 0.1)
				(type default)
			)
			(layer "B.Fab")
		)
		(fp_line
			(start 0.67945 0.3048)
			(end 0.67945 -0.305054)
			(stroke
				(width 0.1)
				(type default)
			)
			(layer "B.Fab")
		)
		(fp_line
			(start 0.12065 0.3048)
			(end 0.67945 0.3048)
			(stroke
				(width 0.1)
				(type default)
			)
			(layer "B.Fab")
		)
		(fp_line
			(start -0.120396 0.3048)
			(end -0.120396 0.2794)
			(stroke
				(width 0.1)
				(type default)
			)
			(layer "B.Fab")
		)
		(fp_line
			(start -0.67945 0.3048)
			(end -0.120396 0.3048)
			(stroke
				(width 0.1)
				(type default)
			)
			(layer "B.Fab")
		)
		(pad "1" smd circle
			(at 0.40005 0 270)
			(size 0 0)
			(layers "B.Cu" "B.Mask" "B.Paste")
			(net "P0V9_CPU0_RT3_2A")
		)
		(pad "2" smd circle
			(at -0.40005 0 270)
			(size 0 0)
			(layers "B.Cu" "B.Mask" "B.Paste")
			(net "GND")
		)
	)
	(footprint ""
		(layer "B.Cu")
		(at 203.045314 -78.247748 180)
		(property "Reference" "R3244"
			(at 0 0 0)
			(layer "B.SilkS")
			(hide yes)
			(effects
				(font
					(size 1.27 1.27)
				)
				(justify mirror)
			)
		)
		(property "Value" ""
			(at 0 0 0)
			(layer "B.Fab")
			(effects
				(font
					(size 1.27 1.27)
				)
				(justify mirror)
			)
		)
		(duplicate_pad_numbers_are_jumpers no)
		(fp_line
			(start 0.7874 0.4064)
			(end 0.7874 -0.4064)
			(stroke
				(width 0.1524)
				(type default)
			)
			(layer "B.SilkS")
		)
		(fp_line
			(start 0.7874 -0.4064)
			(end -0.7874 -0.4064)
			(stroke
				(width 0.1524)
				(type default)
			)
			(layer "B.SilkS")
		)
		(fp_line
			(start -0.7874 0.4064)
			(end 0.7874 0.4064)
			(stroke
				(width 0.1524)
				(type default)
			)
			(layer "B.SilkS")
		)
		(fp_line
			(start -0.7874 -0.4064)
			(end -0.7874 0.4064)
			(stroke
				(width 0.1524)
				(type default)
			)
			(layer "B.SilkS")
		)
		(fp_line
			(start 0.67945 0.3048)
			(end 0.67945 -0.305054)
			(stroke
				(width 0.1)
				(type default)
			)
			(layer "B.Fab")
		)
		(fp_line
			(start 0.67945 -0.305054)
			(end 0.12065 -0.305054)
			(stroke
				(width 0.1)
				(type default)
			)
			(layer "B.Fab")
		)
		(fp_line
			(start 0.12065 0.3048)
			(end 0.67945 0.3048)
			(stroke
				(width 0.1)
				(type default)
			)
			(layer "B.Fab")
		)
		(fp_line
			(start 0.12065 0.2794)
			(end 0.12065 0.3048)
			(stroke
				(width 0.1)
				(type default)
			)
			(layer "B.Fab")
		)
		(fp_line
			(start 0.12065 -0.2794)
			(end -0.12065 -0.2794)
			(stroke
				(width 0.1)
				(type default)
			)
			(layer "B.Fab")
		)
		(fp_line
			(start 0.12065 -0.305054)
			(end 0.12065 -0.2794)
			(stroke
				(width 0.1)
				(type default)
			)
			(layer "B.Fab")
		)
		(fp_line
			(start -0.120396 0.3048)
			(end -0.120396 0.2794)
			(stroke
				(width 0.1)
				(type default)
			)
			(layer "B.Fab")
		)
		(fp_line
			(start -0.120396 0.2794)
			(end 0.12065 0.2794)
			(stroke
				(width 0.1)
				(type default)
			)
			(layer "B.Fab")
		)
		(fp_line
			(start -0.12065 -0.2794)
			(end -0.12065 -0.3048)
			(stroke
				(width 0.1)
				(type default)
			)
			(layer "B.Fab")
		)
		(fp_line
			(start -0.12065 -0.3048)
			(end -0.67945 -0.3048)
			(stroke
				(width 0.1)
				(type default)
			)
			(layer "B.Fab")
		)
		(fp_line
			(start -0.67945 0.3048)
			(end -0.120396 0.3048)
			(stroke
				(width 0.1)
				(type default)
			)
			(layer "B.Fab")
		)
		(fp_line
			(start -0.67945 -0.3048)
			(end -0.67945 0.3048)
			(stroke
				(width 0.1)
				(type default)
			)
			(layer "B.Fab")
		)
		(pad "1" smd circle
			(at 0.40005 0)
			(size 0 0)
			(layers "B.Cu" "B.Mask" "B.Paste")
			(net "OCP_V3_2_RBT_ARB_OUT")
		)
		(pad "2" smd circle
			(at -0.40005 0)
			(size 0 0)
			(layers "B.Cu" "B.Mask" "B.Paste")
			(net "OCP_V3_2_RBT_ARB_IN_R")
		)
	)
)
